# T6G (Grand Teton) — schematic netlist excerpt (pin names and nets, part order shuffled) for the footprints in the layout excerpt that follows; sources: Cadence DE-HDL packaged netlist, KiCad conversion of 04192023_DAF0TMB3IC0_F0TG_MB_C_brd_V02_OCP.brd

R9043  Q_RES  4.7K 5% CHIP  pkg 0402LF  page 126 : A = P3V3_AUX ; B = GPU_WP_HW_CTRL_ISO
R3196  Q_RES  0 5% CHIP  pkg 0402LF  page 55 : A = CLK_100M_CPU1_CLK03_R_DP ; B = CLK_100M_CPU1_CLK03_DP
PC2081  Q_CAP  10UF 16V 10% X6S  pkg C0805  page 134 : A = P3V3_OCP_SFF_R ; B = GND

(kicad_pcb
	(version 20260206)
	(generator "pcbnew")
	(generator_version "10.0")
	(general
		(thickness 1.6)
		(legacy_teardrops no)
	)
	(paper "A4")
	(title_block
		(title "04192023_DAF0TMB3IC0_F0TG_MB_C_brd_V02_OCP.brd")
		(comment 1 "Grand Teton / footprints 1630-1632 of 8354")
	)
	(layers
		(0 "F.Cu" signal "TOP")
		(4 "In1.Cu" signal "GND")
		(6 "In2.Cu" signal "IN1")
		(8 "In3.Cu" signal "GND1")
		(10 "In4.Cu" signal "IN2")
		(12 "In5.Cu" signal "GND2")
		(14 "In6.Cu" signal "IN3")
		(16 "In7.Cu" signal "GND3")
		(18 "In8.Cu" signal "VCC")
		(20 "In9.Cu" signal "VCC1")
		(22 "In10.Cu" signal "GND4")
		(24 "In11.Cu" signal "IN4")
		(26 "In12.Cu" signal "GND5")
		(28 "In13.Cu" signal "IN5")
		(30 "In14.Cu" signal "GND6")
		(32 "In15.Cu" signal "IN6")
		(34 "In16.Cu" signal "GND7")
		(2 "B.Cu" signal "BOTTOM")
		(9 "F.Adhes" user "F.Adhesive")
		(11 "B.Adhes" user "B.Adhesive")
		(13 "F.Paste" user "Package Geometry/Pastemask Top")
		(15 "B.Paste" user "Package Geometry/Pastemask Bottom")
		(5 "F.SilkS" user "Ref Des/Silkscreen Top")
		(7 "B.SilkS" user "Ref Des/Silkscreen Bottom")
		(1 "F.Mask" user "Board Geometry/Soldermask Top")
		(3 "B.Mask" user "Board Geometry/Soldermask Bottom")
		(17 "Dwgs.User" user "User.Drawings")
		(19 "Cmts.User" user "User.Comments")
		(21 "Eco1.User" user "User.Eco1")
		(23 "Eco2.User" user "User.Eco2")
		(25 "Edge.Cuts" user "Board Geometry/Outline")
		(27 "Margin" user)
		(31 "F.CrtYd" user "Package Geometry/Place Bound Top")
		(29 "B.CrtYd" user "Package Geometry/Place Bound Bottom")
		(35 "F.Fab" user "Ref Des/Assembly Top")
		(33 "B.Fab" user "Ref Des/Assembly Bottom")
	)
	(footprint ""
		(layer "F.Cu")
		(at 444.59652 -434.799232 90)
		(property "Reference" "R9043"
			(at 0 0 90)
			(layer "F.SilkS")
			(hide yes)
			(effects
				(font
					(size 1.27 1.27)
				)
			)
		)
		(property "Value" ""
			(at 0 0 90)
			(layer "F.Fab")
			(effects
				(font
					(size 1.27 1.27)
				)
			)
		)
		(duplicate_pad_numbers_are_jumpers no)
		(fp_line
			(start 0.7874 -0.4064)
			(end 0.7874 0.4064)
			(stroke
				(width 0.1524)
				(type default)
			)
			(layer "F.SilkS")
		)
		(fp_line
			(start -0.7874 -0.4064)
			(end 0.7874 -0.4064)
			(stroke
				(width 0.1524)
				(type default)
			)
			(layer "F.SilkS")
		)
		(fp_line
			(start 0.7874 0.4064)
			(end -0.7874 0.4064)
			(stroke
				(width 0.1524)
				(type default)
			)
			(layer "F.SilkS")
		)
		(fp_line
			(start -0.7874 0.4064)
			(end -0.7874 -0.4064)
			(stroke
				(width 0.1524)
				(type default)
			)
			(layer "F.SilkS")
		)
		(fp_line
			(start -0.12065 -0.305054)
			(end -0.12065 -0.2794)
			(stroke
				(width 0.1)
				(type default)
			)
			(layer "F.Fab")
		)
		(fp_line
			(start -0.67945 -0.305054)
			(end -0.12065 -0.305054)
			(stroke
				(width 0.1)
				(type default)
			)
			(layer "F.Fab")
		)
		(fp_line
			(start 0.67945 -0.3048)
			(end 0.67945 0.3048)
			(stroke
				(width 0.1)
				(type default)
			)
			(layer "F.Fab")
		)
		(fp_line
			(start 0.12065 -0.3048)
			(end 0.67945 -0.3048)
			(stroke
				(width 0.1)
				(type default)
			)
			(layer "F.Fab")
		)
		(fp_line
			(start 0.12065 -0.2794)
			(end 0.12065 -0.3048)
			(stroke
				(width 0.1)
				(type default)
			)
			(layer "F.Fab")
		)
		(fp_line
			(start -0.12065 -0.2794)
			(end 0.12065 -0.2794)
			(stroke
				(width 0.1)
				(type default)
			)
			(layer "F.Fab")
		)
		(fp_line
			(start 0.120396 0.2794)
			(end -0.12065 0.2794)
			(stroke
				(width 0.1)
				(type default)
			)
			(layer "F.Fab")
		)
		(fp_line
			(start -0.12065 0.2794)
			(end -0.12065 0.3048)
			(stroke
				(width 0.1)
				(type default)
			)
			(layer "F.Fab")
		)
		(fp_line
			(start 0.67945 0.3048)
			(end 0.120396 0.3048)
			(stroke
				(width 0.1)
				(type default)
			)
			(layer "F.Fab")
		)
		(fp_line
			(start 0.120396 0.3048)
			(end 0.120396 0.2794)
			(stroke
				(width 0.1)
				(type default)
			)
			(layer "F.Fab")
		)
		(fp_line
			(start -0.12065 0.3048)
			(end -0.67945 0.3048)
			(stroke
				(width 0.1)
				(type default)
			)
			(layer "F.Fab")
		)
		(fp_line
			(start -0.67945 0.3048)
			(end -0.67945 -0.305054)
			(stroke
				(width 0.1)
				(type default)
			)
			(layer "F.Fab")
		)
		(pad "1" smd circle
			(at -0.40005 0 90)
			(size 0 0)
			(layers "F.Cu" "F.Mask" "F.Paste")
			(net "P3V3_AUX")
		)
		(pad "2" smd circle
			(at 0.40005 0 90)
			(size 0 0)
			(layers "F.Cu" "F.Mask" "F.Paste")
			(net "GPU_WP_HW_CTRL_ISO")
		)
	)
	(footprint ""
		(layer "F.Cu")
		(at 150.246334 -191.371982 -90)
		(property "Reference" "R3196"
			(at 0 0 270)
			(layer "F.SilkS")
			(hide yes)
			(effects
				(font
					(size 1.27 1.27)
				)
			)
		)
		(property "Value" ""
			(at 0 0 270)
			(layer "F.Fab")
			(effects
				(font
					(size 1.27 1.27)
				)
			)
		)
		(duplicate_pad_numbers_are_jumpers no)
		(fp_line
			(start 0.440182 0.4064)
			(end -0.347218 0.4064)
			(stroke
				(width 0.1524)
				(type default)
			)
			(layer "F.SilkS")
		)
		(fp_line
			(start -0.7874 -0.020066)
			(end -0.7874 -0.4064)
			(stroke
				(width 0.1524)
				(type default)
			)
			(layer "F.SilkS")
		)
		(fp_line
			(start -0.7874 -0.4064)
			(end 0.7874 -0.4064)
			(stroke
				(width 0.1524)
				(type default)
			)
			(layer "F.SilkS")
		)
		(fp_line
			(start 0.7874 -0.4064)
			(end 0.7874 -0.020066)
			(stroke
				(width 0.1524)
				(type default)
			)
			(layer "F.SilkS")
		)
		(fp_line
			(start -0.67945 0.3048)
			(end -0.67945 -0.305054)
			(stroke
				(width 0.1)
				(type default)
			)
			(layer "F.Fab")
		)
		(fp_line
			(start -0.12065 0.3048)
			(end -0.67945 0.3048)
			(stroke
				(width 0.1)
				(type default)
			)
			(layer "F.Fab")
		)
		(fp_line
			(start 0.120396 0.3048)
			(end 0.120396 0.2794)
			(stroke
				(width 0.1)
				(type default)
			)
			(layer "F.Fab")
		)
		(fp_line
			(start 0.67945 0.3048)
			(end 0.120396 0.3048)
			(stroke
				(width 0.1)
				(type default)
			)
			(layer "F.Fab")
		)
		(fp_line
			(start -0.12065 0.2794)
			(end -0.12065 0.3048)
			(stroke
				(width 0.1)
				(type default)
			)
			(layer "F.Fab")
		)
		(fp_line
			(start 0.120396 0.2794)
			(end -0.12065 0.2794)
			(stroke
				(width 0.1)
				(type default)
			)
			(layer "F.Fab")
		)
		(fp_line
			(start -0.12065 -0.2794)
			(end 0.12065 -0.2794)
			(stroke
				(width 0.1)
				(type default)
			)
			(layer "F.Fab")
		)
		(fp_line
			(start 0.12065 -0.2794)
			(end 0.12065 -0.3048)
			(stroke
				(width 0.1)
				(type default)
			)
			(layer "F.Fab")
		)
		(fp_line
			(start 0.12065 -0.3048)
			(end 0.67945 -0.3048)
			(stroke
				(width 0.1)
				(type default)
			)
			(layer "F.Fab")
		)
		(fp_line
			(start 0.67945 -0.3048)
			(end 0.67945 0.3048)
			(stroke
				(width 0.1)
				(type default)
			)
			(layer "F.Fab")
		)
		(fp_line
			(start -0.67945 -0.305054)
			(end -0.12065 -0.305054)
			(stroke
				(width 0.1)
				(type default)
			)
			(layer "F.Fab")
		)
		(fp_line
			(start -0.12065 -0.305054)
			(end -0.12065 -0.2794)
			(stroke
				(width 0.1)
				(type default)
			)
			(layer "F.Fab")
		)
		(pad "1" smd circle
			(at -0.40005 0 270)
			(size 0 0)
			(layers "F.Cu" "F.Mask" "F.Paste")
			(net "CLK_100M_CPU1_CLK03_R_DP")
		)
		(pad "2" smd circle
			(at 0.40005 0 270)
			(size 0 0)
			(layers "F.Cu" "F.Mask" "F.Paste")
			(net "CLK_100M_CPU1_CLK03_DP")
		)
	)
	(footprint ""
		(layer "F.Cu")
		(at 426.6819 -109.644688 90)
		(property "Reference" "PC2081"
			(at 0 0 90)
			(layer "F.SilkS")
			(hide yes)
			(effects
				(font
					(size 1.27 1.27)
				)
			)
		)
		(property "Value" ""
			(at 0 0 90)
			(layer "F.Fab")
			(effects
				(font
					(size 1.27 1.27)
				)
			)
		)
		(duplicate_pad_numbers_are_jumpers no)
		(fp_line
			(start 1.524 -0.762)
			(end 1.524 0.762)
			(stroke
				(width 0.1524)
				(type default)
			)
			(layer "F.SilkS")
		)
		(fp_line
			(start -1.524 -0.762)
			(end 1.524 -0.762)
			(stroke
				(width 0.1524)
				(type default)
			)
			(layer "F.SilkS")
		)
		(fp_line
			(start 1.524 0.762)
			(end -1.524 0.762)
			(stroke
				(width 0.1524)
				(type default)
			)
			(layer "F.SilkS")
		)
		(fp_line
			(start -1.524 0.762)
			(end -1.524 -0.762)
			(stroke
				(width 0.1524)
				(type default)
			)
			(layer "F.SilkS")
		)
		(fp_line
			(start 1.1049 -0.724916)
			(end -1.1049 -0.724916)
			(stroke
				(width 0.1)
				(type default)
			)
			(layer "F.Fab")
		)
		(fp_line
			(start -1.1049 -0.724916)
			(end -1.1049 0.724916)
			(stroke
				(width 0.1)
				(type default)
			)
			(layer "F.Fab")
		)
		(fp_line
			(start 1.1049 0.724916)
			(end 1.1049 -0.724916)
			(stroke
				(width 0.1)
				(type default)
			)
			(layer "F.Fab")
		)
		(fp_line
			(start -1.1049 0.724916)
			(end 1.1049 0.724916)
			(stroke
				(width 0.1)
				(type default)
			)
			(layer "F.Fab")
		)
		(pad "1" smd rect
			(at -0.889 0 270)
			(size 1.016 1.27)
			(layers "F.Cu" "F.Mask" "F.Paste")
			(net "P3V3_OCP_SFF_R")
		)
		(pad "2" smd rect
			(at 0.889 0 270)
			(size 1.016 1.27)
			(layers "F.Cu" "F.Mask" "F.Paste")
			(net "GND")
		)
	)
)
